# TIMECARD (Time Appliance Project (Time Card)) — schematic parts with pin connectivity, parts 166–330 of 1119; source: Cadence DE-HDL packaged netlist (pstxprt.dat, pstxnet.dat, pstchip.dat)

C166  CAPACITOR  0.1UF 10V 10%  pkg SMC_0402R_H022  page 14 : 1 = XP1R0V_FPGA_VCCINT ; 2 = SG
C167  CAPACITOR  4.7UF 6.3V 20%  pkg SMC_0402R_H026  page 14 : 1 = XP3R3V_FPGA ; 2 = SG
C168  CAPACITOR  22UF 10V 20%  pkg SMC_0805R_H057  page 14 : 1 = XP2R5V_FPGA ; 2 = SG
C169  CAPACITOR  0.1UF 10V 10%  pkg SMC_0402R_H022  page 14 : 1 = XP1R0V_FPGA_VCCINT ; 2 = SG
C170  CAPACITOR  4.7UF 6.3V 20%  pkg SMC_0402R_H026  page 14 : 1 = XP3R3V_FPGA ; 2 = SG
C171  CAPACITOR  0.1UF 10V 10%  pkg SMC_0402R_H022  page 14 : 1 = XP1R0V_FPGA_VCCINT ; 2 = SG
C172  CAPACITOR  100UF 6.3V 20%  pkg SMC_1210R_H110  page 14 : 1 = XP3R3V_FPGA ; 2 = SG
C173  CAPACITOR  47UF 4V 20%  pkg SMC_0805R_H057  page 14 : 1 = XP1R0V_FPGA_VCCINT ; 2 = SG
C174  CAPACITOR  100UF 6.3V 20%  pkg SMC_1210R_H110  page 14 : 1 = XP3R3V_FPGA ; 2 = SG
C175  CAPACITOR  100UF 6.3V 20%  pkg SMC_1210R_H110  page 14 : 1 = XP1R0V_FPGA_VCCINT ; 2 = SG
C176  CAPACITOR  100UF 6.3V 20%  pkg SMC_1210R_H110  page 14 : 1 = XP1R0V_FPGA_VCCINT ; 2 = SG
C177  CAPACITOR  100UF 6.3V 20%  pkg SMC_1210R_H110  page 14 : 1 = XP1R0V_FPGA_VCCINT ; 2 = SG
C178  CAPACITOR  0.1UF 10V 10%  pkg SMC_0402R_H022  page 14 : 1 = XP1R0V_FPGA ; 2 = SG
C179  CAPACITOR  47UF 4V 20%  pkg SMC_0805R_H057  page 14 : 1 = XP1R0V_FPGA ; 2 = SG
C180  CAPACITOR  22UF 10V 20%  pkg SMC_0805R_H057  page 30 : 1 = XP3R3V ; 2 = SG
C181  CAPACITOR  22UF 10V 20%  pkg SMC_0805R_H057  page 30 : 1 = XP3R3V ; 2 = SG
C182  CAPACITOR  0.1UF 25V 10%  pkg SMC_0402R_H022  page 30 : 1 = XP3R3V ; 2 = SG
C183  CAPACITOR  0.1UF 25V 10% X7R  pkg SMC_0402R_H022  page 30 : 1 = XP3R3V ; 2 = SG
C184  CAPACITOR  0.1UF 25V 10%  pkg SMC_0402R_H022  page 30 : 1 = XP1R2V_EN_R ; 2 = SG
C185  CAPACITOR  10UF 25V 20%  pkg SMC_0805R_H057  page 30 : 1 = XP1R2V_VIN ; 2 = SG
C186  CAPACITOR  10UF 25V 20%  pkg SMC_0805R_H057  page 30 : 1 = XP1R8V_VIN ; 2 = SG
C187  CAPACITOR  0.1UF 25V 10%  pkg SMC_0402R_H022  page 30 : 1 = XP1R8V_EN_R ; 2 = SG
C188  CAPACITOR  0.1UF 25V 10%  pkg SMC_0402R_H022  page 30 : 1 = XP1R2V_VIN ; 2 = SG
C189  CAPACITOR  0.1UF 25V 10%  pkg SMC_0402R_H022  page 30 : 1 = XP1R8V_VIN ; 2 = SG
C190  CAPACITOR  0.01UF 25V 10%  pkg SMC_0201R  page 30 : 1 = XP1R2V_SS ; 2 = SG
C191  CAPACITOR  0.01UF 25V 10%  pkg SMC_0201R  page 30 : 1 = XP1R8V_SS ; 2 = SG
C192  CAPACITOR  0.01UF 25V 10%  pkg SMC_0201R  page 30 : 1 = XP1R2V_PG_R ; 2 = SG
C193  CAPACITOR  0.01UF 25V 10%  pkg SMC_0201R  page 30 : 1 = XP1R8V_PG_R ; 2 = SG
C194  CAPACITOR  10UF 25V 20%  pkg SMC_0805R_H057  page 30 : 1 = XP1R2V_FPGA ; 2 = SG
C195  CAPACITOR  10UF 25V 20%  pkg SMC_0805R_H057  page 30 : 1 = XP1R8V_FPGA ; 2 = SG
C196  CAPACITOR  0.1UF 25V 10%  pkg SMC_0402R_H022  page 30 : 1 = XP1R2V_FPGA ; 2 = SG
C197  CAPACITOR  0.1UF 25V 10%  pkg SMC_0402R_H022  page 30 : 1 = XP1R8V_FPGA ; 2 = SG
C198  CAPACITOR  4.7UF 6.3V 20%  pkg SMC_0402R_H026  page 10 : 1 = XP3R3V_FPGA ; 2 = SG
C199  CAPACITOR  0.1UF 10V 10%  pkg SMC_0402R_H022  page 10 : 1 = XP3R3V_FPGA ; 2 = SG
C200  CAPACITOR  0.1UF 10V 10%  pkg SMC_0402R_H022  page 14 : 1 = XP1R8V_FPGA_VCCAUX ; 2 = SG
C201  CAPACITOR  0.1UF 10V 10%  pkg SMC_0402R_H022  page 14 : 1 = XP1R0V_FPGA_VCCINT ; 2 = SG
C202  CAPACITOR  0.1UF 10V 10%  pkg SMC_0402R_H022  page 14 : 1 = XP3R3V_FPGA ; 2 = SG
C203  CAPACITOR  0.1UF 10V 10%  pkg SMC_0402R_H022  page 14 : 1 = XP3R3V_FPGA ; 2 = SG
C204  CAPACITOR  0.1UF 10V 10%  pkg SMC_0402R_H022  page 14 : 1 = XP2R5V_FPGA ; 2 = SG
C205  CAPACITOR  0.1UF 10V 10%  pkg SMC_0402R_H022  page 14 : 1 = FPGA_MGTAVTT ; 2 = SG
C206  CAPACITOR  0.1UF 10V 10%  pkg SMC_0402R_H022  page 14 : 1 = XP1R8V_FPGA_VCCAUX ; 2 = SG
C207  CAPACITOR  0.1UF 10V 10%  pkg SMC_0402R_H022  page 14 : 1 = XP1R0V_FPGA_VCCINT ; 2 = SG
C208  CAPACITOR  0.1UF 10V 10%  pkg SMC_0402R_H022  page 14 : 1 = XP2R5V_FPGA ; 2 = SG
C209  CAPACITOR  0.1UF 10V 10%  pkg SMC_0402R_H022  page 14 : 1 = FPGA_MGTAVTT ; 2 = SG
C210  CAPACITOR  0.1UF 10V 10%  pkg SMC_0402R_H022  page 14 : 1 = XP3R3V_FPGA ; 2 = SG
C211  CAPACITOR  0.1UF 10V 10%  pkg SMC_0402R_H022  page 14 : 1 = XP3R3V_FPGA ; 2 = SG
C212  CAPACITOR  0.1UF 10V 10%  pkg SMC_0402R_H022  page 14 : 1 = XP1R8V_FPGA_VCCAUX ; 2 = SG
C213  CAPACITOR  0.1UF 10V 10%  pkg SMC_0402R_H022  page 14 : 1 = XP2R5V_FPGA ; 2 = SG
C214  CAPACITOR  0.1UF 10V 10%  pkg SMC_0402R_H022  page 14 : 1 = XP1R0V_FPGA_VCCINT ; 2 = SG
C215  CAPACITOR  0.1UF 10V 10%  pkg SMC_0402R_H022  page 14 : 1 = XP3R3V_FPGA ; 2 = SG
C216  CAPACITOR  0.1UF 10V 10%  pkg SMC_0402R_H022  page 14 : 1 = XP3R3V_FPGA ; 2 = SG
C217  CAPACITOR  0.1UF 10V 10%  pkg SMC_0402R_H022  page 14 : 1 = FPGA_MGTAVTT ; 2 = SG
C218  CAPACITOR  0.1UF 10V 10%  pkg SMC_0402R_H022  page 14 : 1 = XP1R0V_FPGA_MGTAVCC ; 2 = SG
C219  CAPACITOR  0.1UF 10V 10%  pkg SMC_0402R_H022  page 14 : 1 = XP1R8V_FPGA_VCCAUX ; 2 = SG
C220  CAPACITOR  0.1UF 10V 10%  pkg SMC_0402R_H022  page 14 : 1 = XP2R5V_FPGA ; 2 = SG
C221  CAPACITOR  0.1UF 10V 10%  pkg SMC_0402R_H022  page 14 : 1 = XP3R3V_FPGA ; 2 = SG
C222  CAPACITOR  0.1UF 10V 10%  pkg SMC_0402R_H022  page 14 : 1 = XP1R0V_FPGA_VCCINT ; 2 = SG
C223  CAPACITOR  0.1UF 10V 10%  pkg SMC_0402R_H022  page 14 : 1 = XP3R3V_FPGA ; 2 = SG
C224  CAPACITOR  22UF 10V 20%  pkg SMC_0805R_H057  page 31 : 1 = XP3R3V ; 2 = SG
C225  CAPACITOR  0.1UF 25V 10%  pkg SMC_0402R_H022  page 16 : 1 = XP3R3V_FPGA ; 2 = SG
C226  CAPACITOR  0.1UF 25V 10% X7R  pkg SMC_0402R_H022  page 31 : 1 = XP3R3V ; 2 = SG
C227  CAPACITOR  0.1UF 25V 10%  pkg SMC_0402R_H022  page 31 : 1 = UNNAMED_515_CAPACITOR_I128_1 ; 2 = SG
C228  CAPACITOR  10UF 25V 20%  pkg SMC_0805R_H057  page 31 : 1 = UNNAMED_515_CAPACITOR_I130_1 ; 2 = SG
C229  CAPACITOR  0.1UF 10V 10%  pkg SMC_0402R_H022  page 31 : 1 = XP3R3V_FPGA_EN_R ; 2 = SG
C230  CAPACITOR  0.1UF 25V 10%  pkg SMC_0402R_H022  page 31 : 1 = UNNAMED_515_CAPACITOR_I130_1 ; 2 = SG
C231  CAPACITOR  0.01UF 25V 10%  pkg SMC_0201R  page 31 : 1 = UNNAMED_515_CAPACITOR_I132_1 ; 2 = SG
C232  CAPACITOR  22UF 10V 20%  pkg SMC_0805R_H057  page 31 : 1 = XP3R3V ; 2 = SG
C233  CAPACITOR  0.1UF 10V 10%  pkg SMC_0402R_H022  page 31 : 1 = XP3R3V ; 2 = SG
C234  CAPACITOR  0.01UF 25V 10%  pkg SMC_0201R  page 31 : 1 = UNNAMED_515_CAPACITOR_I138_1 ; 2 = SG
C235  CAPACITOR  0.1UF 10V 10%  pkg SMC_0402R_H022  page 31 : 1 = XP3R3V ; 2 = SG
C236  CAPACITOR  0.1UF 25V 10%  pkg SMC_0402R_H022  page 31 : 1 = XP3R3V_FPGA_SR ; 2 = SG
C237  CAPACITOR  0.1UF 10V 10%  pkg SMC_0402R_H022  page 31 : 1 = XP3R3V_FPGA ; 2 = SG
C238  CAPACITOR  22UF 10V 20%  pkg SMC_0805R_H057  page 31 : 1 = XP3R3V_FPGA ; 2 = SG
C239  CAPACITOR  10UF 25V 20%  pkg SMC_0805R_H057  page 31 : 1 = XP2R5V_FPGA ; 2 = SG
C240  CAPACITOR  22UF 10V 20%  pkg SMC_0805R_H057  page 31 : 1 = XP3R3V_FPGA ; 2 = SG
C241  CAPACITOR  22UF 10V 20%  pkg SMC_0805R_H057  page 31 : 1 = XP3R3V_FPGA ; 2 = SG
C242  CAPACITOR  0.1UF 25V 10%  pkg SMC_0402R_H022  page 31 : 1 = XP2R5V_FPGA ; 2 = SG
C243  CAPACITOR  22UF 10V 20%  pkg SMC_0805R_H057  page 31 : 1 = XP3R3V_FPGA ; 2 = SG
C244  CAPACITOR  0.1UF 25V 10%  pkg SMC_0402R_H022  page 15 : 1 = XP3R3V ; 2 = SG
C245  CAPACITOR  0.1UF 25V 10%  pkg SMC_0402R_H022  page 15 : 1 = XP3R3V ; 2 = SG
C246  CAPACITOR  10UF 6.3V 20%  pkg SMC_0402R_H022  page 15 : 1 = VDD3V3_OSC_200M ; 2 = SG
C247  CAPACITOR  10UF 6.3V 20%  pkg SMC_0402R_H022  page 15 : 1 = VDD3V3_OSC_125M ; 2 = SG
C248  CAPACITOR  0.1UF 25V 10%  pkg SMC_0402R_H022  page 15 : 1 = VDD3V3_OSC_200M ; 2 = SG
C249  CAPACITOR  0.1UF 25V 10%  pkg SMC_0402R_H022  page 15 : 1 = VDD3V3_OSC_125M ; 2 = SG
C250  CAPACITOR  0.1UF 25V 10%  pkg SMC_0402R_H022  page 9 : 1 = UNNAMED_3_RESISTOR_I151_2 ; 2 = SG
C251  CAPACITOR  0.1UF 10V 10%  pkg SMC_0402R_H022  page 15 : 1 = OSC_200M_CLKP ; 2 = MHZ200CLKP_CLKIN
C252  CAPACITOR  0.1UF 10V 10%  pkg SMC_0402R_H022  page 15 : 1 = OSC_200M_CLKN ; 2 = MHZ200CLKN_CLKIN
C253  CAPACITOR  0.1UF 10V 10%  pkg SMC_0402R_H022  page 15 : 1 = OSC_125M_CLKP ; 2 = MHZ125CLKP_CLKIN
C254  CAPACITOR  0.1UF 10V 10%  pkg SMC_0402R_H022  page 15 : 1 = OSC_125M_CLKN ; 2 = MHZ125CLKN_CLKIN
C255  CAPACITOR  0.1UF 25V 10%  pkg SMC_0402R_H022  page 29 : 1 = XP12R0V ; 2 = SG
C256  CAPACITOR  0.1UF 10V 10%  pkg SMC_0402R_H022  page 29 : 1 = UNNAMED_523_CAPACITOR_I7_1 ; 2 = SG
C257  CAPACITOR  10UF 25V 20%  pkg SMC_0805R_H057  page 29 : 1 = VIN_XP1R0V ; 2 = SG
C258  CAPACITOR  0.01UF 25V 10%  pkg SMC_0201R  page 29 : 1 = SG ; 2 = XP1R0V_PG
C259  CAPACITOR  0.022UF 25V 10%  pkg SMC_0402R_H022  page 29 : 1 = XP1R0V_SS ; 2 = XP1R0V_AGND
C260  CAPACITOR  10UF 25V 20%  pkg SMC_0805R_H057  page 29 : 1 = VIN_XP1R0V ; 2 = SG
C261  CAPACITOR  0.1UF 25V 10%  pkg SMC_0402R_H022  page 29 : 1 = VIN_XP1R0V ; 2 = SG
C262  CAPACITOR  0.1UF 25V 10%  pkg SMC_0402R_H022  page 29 : 1 = VIN_XP1R0V ; 2 = SG
C263  CAPACITOR  4700PF 25V 10%  pkg SMC_0201R  page 29 : 1 = UNNAMED_523_CAPACITOR_I9_1 ; 2 = XP1R0V_AGND
C264  CAPACITOR  18PF 25V 5%  pkg SMC_0201R  page 29 : 1 = XP1R0V_COMP ; 2 = XP1R0V_AGND
C265  CAPACITOR  0.1UF 25V 10%  pkg SMC_0402R_H022  page 29 : 1 = UNNAMED_523_CAPACITOR_I24_1 ; 2 = XP1R0V_SW
C266  CAPACITOR  1000PF 50V 5%  pkg SMC_0402R_H022  page 29 : 1 = XP1R0V_SW ; 2 = UNNAMED_523_CAPACITOR_I31_2
C267  CAPACITOR  100PF 10%  pkg SMC_0201R  page 29 : 1 = UNNAMED_523_CAPACITOR_I28_1 ; 2 = XP1R0V_FB_R_TO_AGND
C268  CAPACITOR  0.1UF 10V 10%  pkg SMC_0402R_H022  page 29 : 1 = XP1R0V_FPGA ; 2 = SG
C269  CAPACITOR  47UF 4V 20%  pkg SMC_0805R_H057  page 29 : 1 = XP1R0V_FPGA ; 2 = SG
C270  CAPACITOR  47UF 4V 20%  pkg SMC_0805R_H057  page 29 : 1 = XP1R0V_FPGA ; 2 = SG
C271  CAPACITOR  47UF 4V 20%  pkg SMC_0805R_H057  page 29 : 1 = XP1R0V_FPGA ; 2 = SG
C272  CAPACITOR  0.1UF 25V 10%  pkg SMC_0402R_H022  page 22 : 1 = XP5R0V ; 2 = SG
C273  CAPACITOR  0.1UF 10V 10%  pkg SMC_0402R_H022  page 22 : 1 = XP3R3V_GPS ; 2 = SG
C274  CAPACITOR  10UF 6.3V 20%  pkg SMC_0402R_H022  page 18 : 1 = VDD3V3_SHT31A ; 2 = SG
C275  CAPACITOR  0.1UF 25V 10%  pkg SMC_0402R_H022  page 18 : 1 = VDD3V3_SHT31A ; 2 = SG
C276  CAPACITOR  0.1UF 25V 10%  pkg SMC_0402R_H022  page 19 : 1 = XP1R8V_FPGA ; 2 = SG
C277  CAPACITOR  10UF 6.3V 20%  pkg SMC_0402R_H022  page 19 : 1 = XP1R8V_ICP10100 ; 2 = SG
C278  CAPACITOR  0.1UF 25V 10%  pkg SMC_0402R_H022  page 19 : 1 = XP1R8V_ICP10100 ; 2 = SG
C279  CAPACITOR  0.1UF 25V 10%  pkg SMC_0402R_H022  page 20 : 1 = XP3R3V_FPGA ; 2 = SG
C280  CAPACITOR  10UF 6.3V 20%  pkg SMC_0402R_H022  page 20 : 1 = VDD_BNO085 ; 2 = SG
C281  CAPACITOR  0.1UF 25V 10%  pkg SMC_0402R_H022  page 20 : 1 = VDD_BNO085 ; 2 = SG
C282  CAPACITOR  10UF 25V 20%  pkg SMC_0805R_H057  page 21 : 1 = XP5R0V_MAC ; 2 = SG
C283  CAPACITOR  10UF 25V 20%  pkg SMC_0805R_H057  page 21 : 1 = XP5R0V_MAC ; 2 = SG
C284  CAPACITOR  22UF 10V 20%  pkg SMC_0805R_H057  page 33 : 1 = UNNAMED_525_CAPACITOR_I7_1 ; 2 = SG
C285  CAPACITOR  0.1UF 10V 10%  pkg SMC_0402R_H022  page 20 : 1 = UNNAMED_9_BNO080LGA28_I29_CAP ; 2 = SG
C286  CAPACITOR  0.22UF 25V 10%  pkg SMC_0402R_H022  page 28 : 1 = XP3R3V_EN ; 2 = SG
C287  CAPACITOR  10UF 6.3V 20%  pkg SMC_0402R_H022  page 9 : 1 = XP3R3V_AUX_PCIE ; 2 = SG
C288  CAPACITOR  0.1UF 25V 10%  pkg SMC_0402R_H022  page 9 : 1 = XP3R3V_AUX_PCIE ; 2 = SG
C289  CAPACITOR  10UF 6.3V 20%  pkg SMC_0402R_H022  page 9 : 1 = XP3R3V_PCIE ; 2 = SG
C290  CAPACITOR  0.1UF 25V 10%  pkg SMC_0402R_H022  page 9 : 1 = XP3R3V_PCIE ; 2 = SG
C291  CAPACITOR  22UF 10V 20%  pkg SMC_0805R_H057  page 14 : 1 = XP2R5V_FPGA ; 2 = SG
C292  CAPACITOR  22UF 10V 20%  pkg SMC_0805R_H057  page 14 : 1 = XP2R5V_FPGA ; 2 = SG
C293  CAPACITOR  0.22UF 25V 10%  pkg SMC_0402R_H022  page 31 : 1 = UNNAMED_515_CAPACITOR_I128_1 ; 2 = SG
C294  CAPACITOR  0.22UF 25V 10%  pkg SMC_0402R_H022  page 31 : 1 = XP3R3V_FPGA_EN_R ; 2 = SG
C297  CAPACITOR  10UF 25V 20%  pkg SMC_0805R_H057  page 27 : 1 = XP12R0V_IN ; 2 = SG
C298  CAPACITOR  0.1UF 25V 10% X7R  pkg SMC_0402R_H022  page 33 : 1 = UNNAMED_525_CAPACITOR_I7_1 ; 2 = SG
C299  CAPACITOR  10UF 25V 20%  pkg SMC_0805R_H057  page 27 : 1 = XP12R0V_IN ; 2 = SG
C300  CAPACITOR  10UF 25V 20%  pkg SMC_0805R_H057  page 33 : 1 = UNNAMED_525_CAPACITOR_I16_1 ; 2 = SG
C301  CAPACITOR  10UF 25V 20%  pkg SMC_0805R_H057  page 27 : 1 = XP12R0V_IN ; 2 = SG
C302  CAPACITOR  0.1UF 25V 10%  pkg SMC_0402R_H022  page 33 : 1 = UNNAMED_525_CAPACITOR_I14_1 ; 2 = SG
C303  CAPACITOR  10UF 25V 20%  pkg SMC_0805R_H057  page 27 : 1 = XP12R0V_IN ; 2 = SG
C304  CAPACITOR  0.1UF 25V 10%  pkg SMC_0402R_H022  page 33 : 1 = UNNAMED_525_CAPACITOR_I16_1 ; 2 = SG
C305  CAPACITOR  0.1UF 25V 10%  pkg SMC_0402R_H022  page 17 : 1 = SG ; 2 = XP3R3V_FPGA
C306  CAPACITOR  0.1UF 25V 10%  pkg SMC_0402R_H022  page 17 : 1 = SG ; 2 = XP3R3V_FPGA
C307  CAPACITOR  0.01UF 25V 10%  pkg SMC_0201R  page 33 : 1 = UNNAMED_525_CAPACITOR_I18_1 ; 2 = SG
C308  CAPACITOR  10UF 25V 20%  pkg SMC_0805R_H057  page 33 : 1 = XP3R3V_FT4232 ; 2 = SG
C309  CAPACITOR  0.1UF 25V 10%  pkg SMC_0402R_H022  page 33 : 1 = XP3R3V_FT4232 ; 2 = SG
C310  CAPACITOR  18PF 5%  pkg SMC_0201R  page 23 : 1 = SG ; 2 = UNNAMED_12_CAPACITOR_I318_2
C311  CAPACITOR  18PF 5%  pkg SMC_0201R  page 23 : 1 = SG ; 2 = UNNAMED_12_CAPACITOR_I321_2
C312  CAPACITOR  0.1UF 10V 10%  pkg SMC_0402R_H022  page 19 : 1 = XP3R3V ; 2 = SG
C313  CAPACITOR  0.1UF 10V 10%  pkg SMC_0402R_H022  page 19 : 1 = XP1R8V_ICP10100 ; 2 = SG
C314  CAPACITOR  10UF 6.3V 20%  pkg SMC_0402R_H022  page 26 : 1 = XP3R3V_FPGA ; 2 = SG
C315  CAPACITOR  0.1UF 25V 10%  pkg SMC_0402R_H022  page 26 : 1 = XP3R3V_FPGA ; 2 = SG
C316  CAPACITOR  0.1UF 25V 10%  pkg SMC_0402R_H022  page 26 : 1 = RGB_LED_SHUTDOWN_N ; 2 = SG
C317  CAPACITOR  18PF 5%  pkg SMC_0201R  page 23 : 1 = SG ; 2 = UNNAMED_12_CAPACITOR_I328_2
C318  CAPACITOR  18PF 5%  pkg SMC_0201R  page 23 : 1 = SG ; 2 = UNNAMED_12_CAPACITOR_I332_2
CR1  DIODE_2F  pkg SMC_CR_067X049_V1  page 33 : A = XP5R0V ; C = UNNAMED_525_CAPACITOR_I7_1
CR2  DIODE_2F  pkg SMC_CR_067X049_V1  page 33 : A = XP5R0V_FT4232 ; C = UNNAMED_525_CAPACITOR_I7_1
CR3  DIODE_2  pkg SMC_CR_170X143_V2  page 27 : A = SG ; C = XP12R0V

CR4  DIODE_4_V1  pkg SOT143  page 23
  1  GND  GROUND  = SG
  2  IO1  BI  = SMA2_SIG_IO_CONN
  3  IO2  BI  = SMA1_SIG_IO_CONN
  4  VDD  POWER  = NC

CR5  DIODE_4_V1  pkg SOT143  page 23
  1  GND  GROUND  = SG
  2  IO1  BI  = SMA4_SIG_IO_CONN
  3  IO2  BI  = SMA3_SIG_IO_CONN
  4  VDD  POWER  = NC

CR6  DIODE_4_V1  pkg SOT143  page 10
  1  GND  GROUND  = SG
  2  IO1  BI  = FT4232_FPGA_TMS
  3  IO2  BI  = FT4232_FPGA_TDI
  4  VDD  POWER  = NC

CR7  DIODE_4_V1  pkg SOT143  page 10
  1  GND  GROUND  = SG
  2  IO1  BI  = FT4232_FPGA_TCK
  3  IO2  BI  = FT4232_FPGA_TDO
  4  VDD  POWER  = NC

CR10  DIODE_2E  pkg SMC_CR_270X232_V1  page 27 : A = SG ; C = XP12R0V_IN

CR12  DIODE_3F  pkg DPAK_3_V3  page 27
  1  A_1  BI  = XP12R0V_PCIE
  2  A_2  BI  = XP12R0V_EXT
  3  C  BI  = XP12R0V_IN

DS1  OPTICAL  pkg SMC_DS_063X031_V4  page 26 : A = UNNAMED_14_OPTICAL_I12_A ; C = LED_DATOUT3
DS2  OPTICAL  pkg SMC_DS_063X031_V4  page 26 : A = UNNAMED_14_OPTICAL_I11_A ; C = LED_DATOUT2
DS3  OPTICAL  pkg SMC_DS_063X031_V4  page 26 : A = UNNAMED_14_OPTICAL_I136_A ; C = LED_DATOUT1
DS4  OPTICAL  pkg SMC_DS_063X031_V4  page 26 : A = UNNAMED_14_OPTICAL_I137_A ; C = LED_DATOUT0
DS5  OPTICAL  pkg SMC_DS_063X031_V4  page 26 : A = UNNAMED_14_OPTICAL_I143_A ; C = SG
